(kicad_pcb
	(version 20260206)
	(generator "pcbnew")
	(generator_version "10.0")
	(general
		(thickness 1.6)
		(legacy_teardrops no)
	)
	(paper "A4")
	(title_block
		(title "baseboard — 13948-1b.1110WZS1818.brd")
		(comment 1 "Honey Badger (Wiwynn) / footprints 912-915 of 2523")
	)
	(layers
		(0 "F.Cu" signal "TOP")
		(4 "In1.Cu" signal "L2GND")
		(6 "In2.Cu" signal "L3")
		(8 "In3.Cu" signal "L4VCC")
		(10 "In4.Cu" signal "L5VCC")
		(12 "In5.Cu" signal "L6")
		(14 "In6.Cu" signal "L7GND")
		(2 "B.Cu" signal "BOTTOM")
		(9 "F.Adhes" user "F.Adhesive")
		(11 "B.Adhes" user "B.Adhesive")
		(13 "F.Paste" user "Package Geometry/Pastemask Top")
		(15 "B.Paste" user "Package Geometry/Pastemask Bottom")
		(5 "F.SilkS" user "Ref Des/Silkscreen Top")
		(7 "B.SilkS" user "Ref Des/Silkscreen Bottom")
		(1 "F.Mask" user "Board Geometry/Soldermask Top")
		(3 "B.Mask" user "Board Geometry/Soldermask Bottom")
		(17 "Dwgs.User" user "User.Drawings")
		(19 "Cmts.User" user "User.Comments")
		(21 "Eco1.User" user "User.Eco1")
		(23 "Eco2.User" user "User.Eco2")
		(25 "Edge.Cuts" user "Board Geometry/Outline")
		(27 "Margin" user)
		(31 "F.CrtYd" user "Package Geometry/Place Bound Top")
		(29 "B.CrtYd" user "Package Geometry/Place Bound Bottom")
		(35 "F.Fab" user "Ref Des/Assembly Top")
		(33 "B.Fab" user "Ref Des/Assembly Bottom")
	)
	(footprint ""
		(layer "F.Cu")
		(at 14.99997 -94.799912 90)
		(property "Reference" "CN4"
			(at 0 0 90)
			(layer "F.SilkS")
			(hide yes)
			(effects
				(font
					(size 1.27 1.27)
				)
			)
		)
		(property "Value" "MLX-CON7-20-GP"
			(at -26.3652 -0.4572 90)
			(unlocked yes)
			(layer "F.Fab")
			(hide yes)
			(effects
				(font
					(size 1.016 1.016)
					(thickness 0.1524)
				)
			)
		)
		(property "Device Type" "74548-0211-U"
			(at -26.3652 -1.9812 90)
			(unlocked yes)
			(layer "F.Fab")
			(hide yes)
			(effects
				(font
					(size 1.016 1.016)
					(thickness 0.1524)
				)
			)
		)
		(duplicate_pad_numbers_are_jumpers no)
		(fp_line
			(start 15.1892 -12.3571)
			(end -16.800068 -12.3571)
			(stroke
				(width 0.1524)
				(type default)
			)
			(layer "F.SilkS")
		)
		(fp_line
			(start -16.800068 -12.3571)
			(end -25.3492 -12.3571)
			(stroke
				(width 0.1524)
				(type default)
			)
			(layer "F.SilkS")
		)
		(fp_line
			(start -16.800068 -12.3571)
			(end -16.800068 12.3571)
			(stroke
				(width 0.1524)
				(type default)
			)
			(layer "F.SilkS")
		)
		(fp_line
			(start -25.3492 -12.3571)
			(end -25.3492 12.3571)
			(stroke
				(width 0.1524)
				(type default)
			)
			(layer "F.SilkS")
		)
		(fp_line
			(start 15.1892 12.3571)
			(end 15.1892 -12.3571)
			(stroke
				(width 0.1524)
				(type default)
			)
			(layer "F.SilkS")
		)
		(fp_line
			(start -16.800068 12.3571)
			(end 15.1892 12.3571)
			(stroke
				(width 0.1524)
				(type default)
			)
			(layer "F.SilkS")
		)
		(fp_line
			(start -25.3492 12.3571)
			(end -16.800068 12.3571)
			(stroke
				(width 0.1524)
				(type default)
			)
			(layer "F.SilkS")
		)
		(fp_circle
			(center 5.999988 -10.104882)
			(end 5.999988 -7.742682)
			(stroke
				(width 0.3048)
				(type default)
			)
			(fill no)
			(layer "F.SilkS")
		)
		(fp_circle
			(center -8.999982 -10.104882)
			(end -8.999982 -7.742682)
			(stroke
				(width 0.3048)
				(type default)
			)
			(fill no)
			(layer "F.SilkS")
		)
		(fp_circle
			(center 5.999988 10.104882)
			(end 5.999988 12.467082)
			(stroke
				(width 0.3048)
				(type default)
			)
			(fill no)
			(layer "F.SilkS")
		)
		(fp_circle
			(center -8.999982 10.104882)
			(end -8.999982 12.467082)
			(stroke
				(width 0.3048)
				(type default)
			)
			(fill no)
			(layer "F.SilkS")
		)
		(fp_poly
			(pts
				(xy -16.800068 -8.86968) (xy -11.3157 -8.86968) (xy -11.3157 -11.469624) (xy -16.800068 -11.469624)
			)
			(stroke
				(width 0)
				(type default)
			)
			(fill yes)
			(layer "F.Paste")
		)
		(fp_poly
			(pts
				(xy -16.800068 -6.023102) (xy -12.599924 -6.023102) (xy -12.599924 -8.20928) (xy -16.800068 -8.20928)
			)
			(stroke
				(width 0)
				(type default)
			)
			(fill yes)
			(layer "F.Paste")
		)
		(fp_poly
			(pts
				(xy -16.800068 -3.176524) (xy -12.599924 -3.176524) (xy -12.599924 -5.362702) (xy -16.800068 -5.362702)
			)
			(stroke
				(width 0)
				(type default)
			)
			(fill yes)
			(layer "F.Paste")
		)
		(fp_poly
			(pts
				(xy -16.800068 -0.329946) (xy -12.599924 -0.329946) (xy -12.599924 -2.516124) (xy -16.800068 -2.516124)
			)
			(stroke
				(width 0)
				(type default)
			)
			(fill yes)
			(layer "F.Paste")
		)
		(fp_poly
			(pts
				(xy -16.800068 2.516632) (xy -12.599924 2.516632) (xy -12.599924 0.330454) (xy -16.800068 0.330454)
			)
			(stroke
				(width 0)
				(type default)
			)
			(fill yes)
			(layer "F.Paste")
		)
		(fp_poly
			(pts
				(xy -16.800068 5.36321) (xy -12.599924 5.36321) (xy -12.599924 3.177032) (xy -16.800068 3.177032)
			)
			(stroke
				(width 0)
				(type default)
			)
			(fill yes)
			(layer "F.Paste")
		)
		(fp_poly
			(pts
				(xy -16.800068 8.209788) (xy -12.599924 8.209788) (xy -12.599924 6.02361) (xy -16.800068 6.02361)
			)
			(stroke
				(width 0)
				(type default)
			)
			(fill yes)
			(layer "F.Paste")
		)
		(fp_poly
			(pts
				(xy -16.800068 11.469624) (xy -11.3157 11.469624) (xy -11.3157 8.86968) (xy -16.800068 8.86968)
			)
			(stroke
				(width 0)
				(type default)
			)
			(fill yes)
			(layer "F.Paste")
		)
		(fp_poly
			(pts
				(xy 8.31215 -8.86968) (xy 11.5697 -8.86968) (xy 11.5697 -4.549648) (xy 13.679932 -4.549648) (xy 13.679932 -11.469624)
				(xy 8.31215 -11.469624)
			)
			(stroke
				(width 0)
				(type default)
			)
			(fill yes)
			(layer "F.Paste")
		)
		(fp_poly
			(pts
				(xy 8.3185 8.86968) (xy 11.5697 8.86968) (xy 11.5697 4.149852) (xy 13.679932 4.149852) (xy 13.679932 11.469624)
				(xy 8.3185 11.469624)
			)
			(stroke
				(width 0)
				(type default)
			)
			(fill yes)
			(layer "F.Paste")
		)
		(fp_poly
			(pts
				(xy -6.68655 -11.469624) (xy 3.68935 -11.469624) (xy 3.68935 -8.86968) (xy 1.0922 -8.86968)
				(arc
					(start 1.0922 -9.373108)
					(mid 0 -10.727704)
					(end -1.0922 -9.373108)
				)
				(xy -1.0922 -8.86968) (xy -6.68655 -8.86968)
			)
			(stroke
				(width 0)
				(type default)
			)
			(fill yes)
			(layer "F.Paste")
		)
		(fp_poly
			(pts
				(xy -6.68655 8.86968) (xy -1.0922 8.86968)
				(arc
					(start -1.0922 9.373108)
					(mid 0 10.727704)
					(end 1.0922 9.373108)
				)
				(xy 1.0922 8.86968) (xy 3.683 8.86968) (xy 3.683 11.469624) (xy -6.68655 11.469624)
			)
			(stroke
				(width 0)
				(type default)
			)
			(fill yes)
			(layer "F.Paste")
		)
		(fp_rect
			(start -25.0952 11.3665)
			(end 14.9352 -11.3665)
			(stroke
				(width 0)
				(type default)
			)
			(fill no)
			(layer "F.CrtYd")
		)
		(fp_poly
			(pts
				(xy -25.6032 12.6111) (xy -25.6032 -12.6111) (xy 15.4432 -12.6111) (xy 15.4432 -8.5725) (xy 14.9352 -8.5725)
				(xy 14.9352 -11.3665) (xy -25.0952 -11.3665) (xy -25.0952 11.3665) (xy 14.9352 11.3665) (xy 14.9352 -8.5598)
				(xy 15.4432 -8.5598) (xy 15.4432 12.6111)
			)
			(stroke
				(width 0)
				(type default)
			)
			(fill no)
			(layer "F.CrtYd")
		)
		(fp_rect
			(start -25.6032 12.6111)
			(end 15.4432 -12.6111)
			(stroke
				(width 0)
				(type default)
			)
			(fill no)
			(layer "F.Fab")
		)
		(pad "" np_thru_hole circle
			(at 0 -9.61009 90)
			(size 0.254 0.254)
			(drill 1.5748)
			(layers "*.Cu" "*.Mask")
			(clearance 1.016)
			(thermal_gap 1.016)
		)
		(pad "" np_thru_hole circle
			(at 0 9.61009 90)
			(size 0.254 0.254)
			(drill 1.5748)
			(layers "*.Cu" "*.Mask")
			(clearance 1.016)
			(thermal_gap 1.016)
		)
		(pad "Z1" thru_hole circle
			(at -8.999982 10.104882 90)
			(size 4.0132 4.0132)
			(drill 2.5146)
			(layers "*.Cu" "*.Mask")
			(remove_unused_layers no)
			(net "GND")
			(clearance -0.2413)
			(thermal_gap 0.3048)
			(padstack
				(mode front_inner_back)
				(layer "Inner"
					(shape circle)
					(size 2.921 2.921)
					(clearance 0.3048)
				)
				(layer "B.Cu"
					(shape circle)
					(size 4.0132 4.0132)
					(clearance -0.2413)
				)
			)
		)
		(pad "Z2" thru_hole circle
			(at 5.999988 10.104882 90)
			(size 4.0132 4.0132)
			(drill 2.5146)
			(layers "*.Cu" "*.Mask")
			(remove_unused_layers no)
			(net "GND")
			(clearance -0.2413)
			(thermal_gap 0.3048)
			(padstack
				(mode front_inner_back)
				(layer "Inner"
					(shape circle)
					(size 2.921 2.921)
					(clearance 0.3048)
				)
				(layer "B.Cu"
					(shape circle)
					(size 4.0132 4.0132)
					(clearance -0.2413)
				)
			)
		)
		(pad "Z3" thru_hole circle
			(at 5.999988 -10.104882 90)
			(size 4.0132 4.0132)
			(drill 2.5146)
			(layers "*.Cu" "*.Mask")
			(remove_unused_layers no)
			(net "GND")
			(clearance -0.2413)
			(thermal_gap 0.3048)
			(padstack
				(mode front_inner_back)
				(layer "Inner"
					(shape circle)
					(size 2.921 2.921)
					(clearance 0.3048)
				)
				(layer "B.Cu"
					(shape circle)
					(size 4.0132 4.0132)
					(clearance -0.2413)
				)
			)
		)
		(pad "Z4" thru_hole circle
			(at -8.999982 -10.104882 90)
			(size 4.0132 4.0132)
			(drill 2.5146)
			(layers "*.Cu" "*.Mask")
			(remove_unused_layers no)
			(net "GND")
			(clearance -0.2413)
			(thermal_gap 0.3048)
			(padstack
				(mode front_inner_back)
				(layer "Inner"
					(shape circle)
					(size 2.921 2.921)
					(clearance 0.3048)
				)
				(layer "B.Cu"
					(shape circle)
					(size 4.0132 4.0132)
					(clearance -0.2413)
				)
			)
		)
		(pad "Z5" smd rect
			(at 12.62507 -2.59969 90)
			(size 2.1082 0.889)
			(layers "F.Cu" "F.Mask" "F.Paste")
			(net "GND")
		)
		(pad "Z6" smd rect
			(at 12.62507 -0.199898 90)
			(size 2.1082 0.889)
			(layers "F.Cu" "F.Mask" "F.Paste")
			(net "GND")
		)
		(pad "Z7" smd rect
			(at 12.62507 2.200148 90)
			(size 2.1082 0.889)
			(layers "F.Cu" "F.Mask" "F.Paste")
			(net "GND")
		)
		(zone
			(layers "F.Cu" "B.Cu" "In1.Cu" "In2.Cu" "In3.Cu" "In4.Cu" "In5.Cu" "In6.Cu")
			(hatch none 0.5)
			(connect_pads
				(clearance 0)
			)
			(min_thickness 0.25)
			(keepout
				(tracks not_allowed)
				(vias allowed)
				(pads allowed)
				(copperpour not_allowed)
				(footprints allowed)
			)
			(placement
				(enabled no)
				(sheetname "")
			)
			(fill
				(thermal_gap 0.5)
				(thermal_bridge_width 0.5)
				(island_removal_mode 0)
			)
			(polygon
				(pts
					(arc
						(start 6.48208 -94.799912)
						(mid 4.29768 -94.799912)
						(end 6.48208 -94.799912)
					)
				)
			)
		)
		(zone
			(layers "F.Cu" "B.Cu" "In1.Cu" "In2.Cu" "In3.Cu" "In4.Cu" "In5.Cu" "In6.Cu")
			(hatch none 0.5)
			(connect_pads
				(clearance 0)
			)
			(min_thickness 0.25)
			(keepout
				(tracks not_allowed)
				(vias allowed)
				(pads allowed)
				(copperpour not_allowed)
				(footprints allowed)
			)
			(placement
				(enabled no)
				(sheetname "")
			)
			(fill
				(thermal_gap 0.5)
				(thermal_bridge_width 0.5)
				(island_removal_mode 0)
			)
			(polygon
				(pts
					(arc
						(start 25.70226 -94.799912)
						(mid 23.51786 -94.799912)
						(end 25.70226 -94.799912)
					)
				)
			)
		)
	)
	(footprint ""
		(layer "F.Cu")
		(at 121.990612 -221.996 180)
		(property "Reference" "SR872"
			(at 0 0 180)
			(layer "F.SilkS")
			(hide yes)
			(effects
				(font
					(size 1.27 1.27)
				)
			)
		)
		(property "Value" "0R2J-2-GP"
			(at 0.064008 -3.993896 180)
			(unlocked yes)
			(layer "F.Fab")
			(hide yes)
			(effects
				(font
					(size 1.016 1.016)
					(thickness 0.1524)
				)
			)
		)
		(property "Device Type" "R402H16"
			(at 0.064008 -5.517896 180)
			(unlocked yes)
			(layer "F.Fab")
			(hide yes)
			(effects
				(font
					(size 1.016 1.016)
					(thickness 0.1524)
				)
			)
		)
		(duplicate_pad_numbers_are_jumpers no)
		(fp_line
			(start 0.508 -0.9398)
			(end -0.508 -0.9398)
			(stroke
				(width 0.1524)
				(type default)
			)
			(layer "F.SilkS")
		)
		(fp_line
			(start -0.508 -0.9398)
			(end -0.508 0.9398)
			(stroke
				(width 0.1524)
				(type default)
			)
			(layer "F.SilkS")
		)
		(fp_rect
			(start -0.508 0.9398)
			(end 0.508 -0.9398)
			(stroke
				(width 0)
				(type default)
			)
			(fill no)
			(layer "F.CrtYd")
		)
		(fp_rect
			(start -0.508 0.9398)
			(end 0.508 -0.9398)
			(stroke
				(width 0)
				(type default)
			)
			(fill no)
			(layer "F.Fab")
		)
		(pad "1" smd custom
			(at 0 -0.4445 180)
			(size 0.1397 0.1397)
			(layers "F.Cu" "F.Mask" "F.Paste")
			(net "REDV_TX7_P")
			(options
				(clearance outline)
				(anchor circle)
			)
			(primitives
				(gr_poly
					(pts
						(arc
							(start -0.1778 -0.2794)
							(mid -0.249642 -0.249642)
							(end -0.2794 -0.1778)
						)
						(arc
							(start -0.2794 0.1778)
							(mid -0.249642 0.249642)
							(end -0.1778 0.2794)
						)
						(arc
							(start 0.1778 0.2794)
							(mid 0.249642 0.249642)
							(end 0.2794 0.1778)
						)
						(arc
							(start 0.2794 -0.1778)
							(mid 0.249642 -0.249642)
							(end 0.1778 -0.2794)
						)
					)
					(width 0)
					(fill yes)
				)
			)
		)
		(pad "2" smd custom
			(at 0 0.4445 180)
			(size 0.1397 0.1397)
			(layers "F.Cu" "F.Mask" "F.Paste")
			(net "SAS_HDD_CONN_TX7_P")
			(options
				(clearance outline)
				(anchor circle)
			)
			(primitives
				(gr_poly
					(pts
						(arc
							(start -0.1778 -0.2794)
							(mid -0.249642 -0.249642)
							(end -0.2794 -0.1778)
						)
						(arc
							(start -0.2794 0.1778)
							(mid -0.249642 0.249642)
							(end -0.1778 0.2794)
						)
						(arc
							(start 0.1778 0.2794)
							(mid 0.249642 0.249642)
							(end 0.2794 0.1778)
						)
						(arc
							(start 0.2794 -0.1778)
							(mid 0.249642 -0.249642)
							(end 0.1778 -0.2794)
						)
					)
					(width 0)
					(fill yes)
				)
			)
		)
	)
	(footprint ""
		(layer "F.Cu")
		(at 53.34 -211.074)
		(property "Reference" "R2113"
			(at 0 0 0)
			(layer "F.SilkS")
			(hide yes)
			(effects
				(font
					(size 1.27 1.27)
				)
			)
		)
		(property "Value" "0R2J-2-GP"
			(at 0.064008 -3.993896 0)
			(unlocked yes)
			(layer "F.Fab")
			(hide yes)
			(effects
				(font
					(size 1.016 1.016)
					(thickness 0.1524)
				)
			)
		)
		(property "Device Type" "R402H16"
			(at 0.064008 -5.517896 0)
			(unlocked yes)
			(layer "F.Fab")
			(hide yes)
			(effects
				(font
					(size 1.016 1.016)
					(thickness 0.1524)
				)
			)
		)
		(duplicate_pad_numbers_are_jumpers no)
		(fp_line
			(start -0.508 -0.9398)
			(end -0.508 0.9398)
			(stroke
				(width 0.1524)
				(type default)
			)
			(layer "F.SilkS")
		)
		(fp_line
			(start 0.508 -0.9398)
			(end -0.508 -0.9398)
			(stroke
				(width 0.1524)
				(type default)
			)
			(layer "F.SilkS")
		)
		(fp_rect
			(start -0.508 0.9398)
			(end 0.508 -0.9398)
			(stroke
				(width 0)
				(type default)
			)
			(fill no)
			(layer "F.CrtYd")
		)
		(fp_rect
			(start -0.508 0.9398)
			(end 0.508 -0.9398)
			(stroke
				(width 0)
				(type default)
			)
			(fill no)
			(layer "F.Fab")
		)
		(pad "1" smd custom
			(at 0 -0.4445)
			(size 0.1397 0.1397)
			(layers "F.Cu" "F.Mask" "F.Paste")
			(net "MB0_SPISS_PD")
			(options
				(clearance outline)
				(anchor circle)
			)
			(primitives
				(gr_poly
					(pts
						(arc
							(start -0.1778 -0.2794)
							(mid -0.249642 -0.249642)
							(end -0.2794 -0.1778)
						)
						(arc
							(start -0.2794 0.1778)
							(mid -0.249642 0.249642)
							(end -0.1778 0.2794)
						)
						(arc
							(start 0.1778 0.2794)
							(mid 0.249642 0.249642)
							(end 0.2794 0.1778)
						)
						(arc
							(start 0.2794 -0.1778)
							(mid 0.249642 -0.249642)
							(end 0.1778 -0.2794)
						)
					)
					(width 0)
					(fill yes)
				)
			)
		)
		(pad "2" smd custom
			(at 0 0.4445)
			(size 0.1397 0.1397)
			(layers "F.Cu" "F.Mask" "F.Paste")
			(net "AGND_CURRENT_MON")
			(options
				(clearance outline)
				(anchor circle)
			)
			(primitives
				(gr_poly
					(pts
						(arc
							(start -0.1778 -0.2794)
							(mid -0.249642 -0.249642)
							(end -0.2794 -0.1778)
						)
						(arc
							(start -0.2794 0.1778)
							(mid -0.249642 0.249642)
							(end -0.1778 0.2794)
						)
						(arc
							(start 0.1778 0.2794)
							(mid 0.249642 0.249642)
							(end 0.2794 0.1778)
						)
						(arc
							(start 0.2794 -0.1778)
							(mid 0.249642 -0.249642)
							(end 0.1778 -0.2794)
						)
					)
					(width 0)
					(fill yes)
				)
			)
		)
	)
	(footprint ""
		(layer "F.Cu")
		(at 79.4766 -15.6718 90)
		(property "Reference" "PC209"
			(at 0 0 90)
			(layer "F.SilkS")
			(hide yes)
			(effects
				(font
					(size 1.27 1.27)
				)
			)
		)
		(property "Value" "SC1U25V3KX-GP"
			(at 0 -2.8194 90)
			(unlocked yes)
			(layer "F.Fab")
			(hide yes)
			(effects
				(font
					(size 1.016 1.016)
					(thickness 0.1524)
				)
			)
		)
		(property "Device Type" "C603H36"
			(at 0 -4.3434 90)
			(unlocked yes)
			(layer "F.Fab")
			(hide yes)
			(effects
				(font
					(size 1.016 1.016)
					(thickness 0.1524)
				)
			)
		)
		(duplicate_pad_numbers_are_jumpers no)
		(fp_line
			(start 0.508 0)
			(end -0.508 0)
			(stroke
				(width 0.2032)
				(type default)
			)
			(layer "F.SilkS")
		)
		(fp_rect
			(start -0.5842 1.3335)
			(end 0.5842 -1.3335)
			(stroke
				(width 0)
				(type default)
			)
			(fill no)
			(layer "F.CrtYd")
		)
		(fp_rect
			(start -0.5842 1.3335)
			(end 0.5842 -1.3335)
			(stroke
				(width 0)
				(type default)
			)
			(fill no)
			(layer "F.Fab")
		)
		(pad "1" smd custom
			(at 0 -0.762 90)
			(size 0.2159 0.2159)
			(layers "F.Cu" "F.Mask" "F.Paste")
			(net "VT235_VDDH")
			(options
				(clearance outline)
				(anchor circle)
			)
			(primitives
				(gr_poly
					(pts
						(arc
							(start -0.3302 -0.4318)
							(mid -0.402042 -0.402042)
							(end -0.4318 -0.3302)
						)
						(arc
							(start -0.4318 0.3302)
							(mid -0.402042 0.402042)
							(end -0.3302 0.4318)
						)
						(arc
							(start 0.3302 0.4318)
							(mid 0.402042 0.402042)
							(end 0.4318 0.3302)
						)
						(arc
							(start 0.4318 -0.3302)
							(mid 0.402042 -0.402042)
							(end 0.3302 -0.4318)
						)
					)
					(width 0)
					(fill yes)
				)
			)
		)
		(pad "2" smd custom
			(at 0 0.762 90)
			(size 0.2159 0.2159)
			(layers "F.Cu" "F.Mask" "F.Paste")
			(net "GND")
			(options
				(clearance outline)
				(anchor circle)
			)
			(primitives
				(gr_poly
					(pts
						(arc
							(start -0.3302 -0.4318)
							(mid -0.402042 -0.402042)
							(end -0.4318 -0.3302)
						)
						(arc
							(start -0.4318 0.3302)
							(mid -0.402042 0.402042)
							(end -0.3302 0.4318)
						)
						(arc
							(start 0.3302 0.4318)
							(mid 0.402042 0.402042)
							(end 0.4318 0.3302)
						)
						(arc
							(start 0.4318 -0.3302)
							(mid 0.402042 -0.402042)
							(end 0.3302 -0.4318)
						)
					)
					(width 0)
					(fill yes)
				)
			)
		)
	)
)
